FILE_TYPE = CONNECTIVITY;
{Allegro Design Entry HDL 17.2-2016 S081 (4005846) 1/11/2022}
"PAGE_NUMBER" = 287;
0"NC";
1"DELTA_L_GND_1\g";
2"DELTA_L_GND_1\g";
3"DELTA_L_GND_1\g";
4"DELTA_L_GND_1\g";
5"DELTA_L_GND_1\g";
6"DELTA_L_GND_1\g";
7"DELTA_L_GND_1\g";
8"DELTA_L_GND_1\g";
9"DELTA_L_GND_1\g";
10"DELTA_L_GND_1\g";
11"DELTA_L_GND_1\g";
12"DELTA_L_GND_1\g";
13"DELTA_L_GND_1\g";
14"DELTA_L_GND_1\g";
15"DELTA_L_GND_1\g";
16"DELTA_L_GND_1\g";
17"DELTA_L_GND_1\g";
18"DELTA_L_GND_1\g";
19"DELTA_L_GND_1\g";
20"DELTA_L_GND_1\g";
21"DELTA_L_GND_1\g";
22"DELTA_L_GND_1\g";
23"DELTA_L_GND_1\g";
24"DELTA_L_GND_1\g";
25"DELTA_L_GND_1\g";
26"DELTA_L_GND_1\g";
27"DELTA_L_GND_1\g";
28"DELTA_L_GND_1\g";
29"DELTA_L_GND_1\g";
30"DELTA_L_GND_1\g";
31"DELTA_L_GND_1\g";
32"DELTA_L_GND_1\g";
33"DELTA_L_85_10INCH_TOP_DP"CDS_PHYS_NET_NAME"DELTA_L_85_10INCH_TOP_DP";
34"DELTA_L_85_10INCH_TOP_DN"CDS_PHYS_NET_NAME"DELTA_L_85_10INCH_TOP_DN";
35"DELTA_L_85_10INCH_IN2_DN"CDS_PHYS_NET_NAME"DELTA_L_85_10INCH_IN2_DN";
36"DELTA_L_85_10INCH_IN2_DP"CDS_PHYS_NET_NAME"DELTA_L_85_10INCH_IN2_DP";
37"DELTA_L_85_10INCH_IN1_DN"CDS_PHYS_NET_NAME"DELTA_L_85_10INCH_IN1_DN";
38"DELTA_L_85_10INCH_IN1_DP"CDS_PHYS_NET_NAME"DELTA_L_85_10INCH_IN1_DP";
39"DELTA_L_85_10INCH_BOT_DN"CDS_PHYS_NET_NAME"DELTA_L_85_10INCH_BOT_DN";
40"DELTA_L_85_10INCH_BOT_DP"CDS_PHYS_NET_NAME"DELTA_L_85_10INCH_BOT_DP";
41"DELTA_L_85_10INCH_IN4_DN"CDS_PHYS_NET_NAME"DELTA_L_85_10INCH_IN4_DN";
42"DELTA_L_85_10INCH_IN4_DP"CDS_PHYS_NET_NAME"DELTA_L_85_10INCH_IN4_DP";
43"DELTA_L_85_10INCH_IN3_DN"CDS_PHYS_NET_NAME"DELTA_L_85_10INCH_IN3_DN";
44"DELTA_L_85_10INCH_IN3_DP"CDS_PHYS_NET_NAME"DELTA_L_85_10INCH_IN3_DP";
45"DELTA_L_85_10INCH_IN6_DN"CDS_PHYS_NET_NAME"DELTA_L_85_10INCH_IN6_DN";
46"DELTA_L_85_10INCH_IN6_DP"CDS_PHYS_NET_NAME"DELTA_L_85_10INCH_IN6_DP";
47"DELTA_L_85_10INCH_IN5_DN"CDS_PHYS_NET_NAME"DELTA_L_85_10INCH_IN5_DN";
48"DELTA_L_85_10INCH_IN5_DP"CDS_PHYS_NET_NAME"DELTA_L_85_10INCH_IN5_DP";
49"DELTA_L_85_5INCH_TOP_DP"CDS_PHYS_NET_NAME"DELTA_L_85_5INCH_TOP_DP";
50"DELTA_L_85_5INCH_TOP_DN"CDS_PHYS_NET_NAME"DELTA_L_85_5INCH_TOP_DN";
51"DELTA_L_85_5INCH_BOT_DN"CDS_PHYS_NET_NAME"DELTA_L_85_5INCH_BOT_DN";
52"DELTA_L_85_5INCH_BOT_DP"CDS_PHYS_NET_NAME"DELTA_L_85_5INCH_BOT_DP";
53"DELTA_L_85_5INCH_IN1_DN"CDS_PHYS_NET_NAME"DELTA_L_85_5INCH_IN1_DN";
54"DELTA_L_85_5INCH_IN1_DP"CDS_PHYS_NET_NAME"DELTA_L_85_5INCH_IN1_DP";
55"DELTA_L_85_5INCH_IN2_DN"CDS_PHYS_NET_NAME"DELTA_L_85_5INCH_IN2_DN";
56"DELTA_L_85_5INCH_IN2_DP"CDS_PHYS_NET_NAME"DELTA_L_85_5INCH_IN2_DP";
57"DELTA_L_85_5INCH_IN3_DN"CDS_PHYS_NET_NAME"DELTA_L_85_5INCH_IN3_DN";
58"DELTA_L_85_5INCH_IN3_DP"CDS_PHYS_NET_NAME"DELTA_L_85_5INCH_IN3_DP";
59"DELTA_L_85_5INCH_IN4_DN"CDS_PHYS_NET_NAME"DELTA_L_85_5INCH_IN4_DN";
60"DELTA_L_85_5INCH_IN4_DP"CDS_PHYS_NET_NAME"DELTA_L_85_5INCH_IN4_DP";
61"DELTA_L_85_5INCH_IN5_DN"CDS_PHYS_NET_NAME"DELTA_L_85_5INCH_IN5_DN";
62"DELTA_L_85_5INCH_IN5_DP"CDS_PHYS_NET_NAME"DELTA_L_85_5INCH_IN5_DP";
63"DELTA_L_85_5INCH_IN6_DN"CDS_PHYS_NET_NAME"DELTA_L_85_5INCH_IN6_DN";
64"DELTA_L_85_5INCH_IN6_DP"CDS_PHYS_NET_NAME"DELTA_L_85_5INCH_IN6_DP";
%"UNIVERSAL_GND"
"1","(-2900,-525)","0","logical_power","I1";
;
HDL_POWER"DELTA_L_GND_1"
CDS_LIB"logical_power";
"A"1;
%"UNIVERSAL_GND"
"1","(-2950,2300)","0","logical_power","I10";
;
HDL_POWER"DELTA_L_GND_1"
CDS_LIB"logical_power";
"A"5;
%"PICOPROBE_BXA"
"1","(-2400,1625)","0","pure_quanta","I11";
;
PART_NUMBER"TP33"
MATERIAL"EMPTY"
PART_TYPE"SMLF"
VALUE"DELTA-L 4.0"
LOCATION"J67"
CDS_LIB"pure_quanta"
CDS_LMAN_SYM_OUTLINE"-150,100,150,-100"
NEEDS_NO_SIZE"TRUE"
$SEC"1"
CDS_SEC"1";
"1_P"
$PN"1"58;
"3_G"
$PN"3"4;
"2_N"
$PN"2"57;
%"PICOPROBE_BXA"
"1","(-2400,2475)","0","pure_quanta","I12";
;
PART_NUMBER"TP33"
PART_TYPE"SMLF"
MATERIAL"EMPTY"
VALUE"DELTA-L 4.0"
LOCATION"J66"
NEEDS_NO_SIZE"TRUE"
CDS_LMAN_SYM_OUTLINE"-150,100,150,-100"
CDS_LIB"pure_quanta"
$SEC"1"
CDS_SEC"1";
"1_P"
$PN"1"56;
"3_G"
$PN"3"5;
"2_N"
$PN"2"55;
%"UNIVERSAL_GND"
"1","(-2950,2875)","0","logical_power","I13";
;
HDL_POWER"DELTA_L_GND_1"
CDS_LIB"logical_power";
"A"6;
%"PICOPROBE_BXA"
"1","(-2400,3050)","0","pure_quanta","I14";
;
PART_NUMBER"TP33"
MATERIAL"EMPTY"
VALUE"DELTA-L 4.0"
PART_TYPE"SMLF"
LOCATION"J65"
NEEDS_NO_SIZE"TRUE"
CDS_LMAN_SYM_OUTLINE"-150,100,150,-100"
CDS_LIB"pure_quanta"
$SEC"1"
CDS_SEC"1";
"1_P"
$PN"1"54;
"3_G"
$PN"3"6;
"2_N"
$PN"2"53;
%"UNIVERSAL_GND"
"1","(-2950,3775)","0","logical_power","I15";
;
HDL_POWER"DELTA_L_GND_1"
CDS_LIB"logical_power";
"A"7;
%"UNIVERSAL_GND"
"1","(-2950,4350)","0","logical_power","I16";
;
HDL_POWER"DELTA_L_GND_1"
CDS_LIB"logical_power";
"A"8;
%"PICOPROBE_BXA"
"1","(-2400,3950)","0","pure_quanta","I17";
;
PART_NUMBER"TP33"
MATERIAL"EMPTY"
PART_TYPE"SMLF"
VALUE"DELTA-L 4.0"
LOCATION"J64"
CDS_LIB"pure_quanta"
CDS_LMAN_SYM_OUTLINE"-150,100,150,-100"
NEEDS_NO_SIZE"TRUE"
$SEC"1"
CDS_SEC"1";
"1_P"
$PN"1"52;
"3_G"
$PN"3"7;
"2_N"
$PN"2"51;
%"PICOPROBE_BXA"
"1","(-2400,4525)","0","pure_quanta","I18";
;
PART_NUMBER"TP33"
MATERIAL"EMPTY"
PART_TYPE"SMLF"
VALUE"DELTA-L 4.0"
LOCATION"J63"
CDS_LMAN_SYM_OUTLINE"-150,100,150,-100"
NEEDS_NO_SIZE"TRUE"
CDS_LIB"pure_quanta"
$SEC"1"
CDS_SEC"1";
"1_P"
$PN"1"49;
"3_G"
$PN"3"8;
"2_N"
$PN"2"50;
%"PICOPROBE_BXA"
"1","(-350,1100)","4","pure_quanta","I19";
;
PART_NUMBER"TP33"
VALUE"DELTA-L 4.0"
PART_TYPE"SMLF"
MATERIAL"EMPTY"
LOCATION"J74"
CDS_LIB"pure_quanta"
CDS_LMAN_SYM_OUTLINE"-150,100,150,-100"
NEEDS_NO_SIZE"TRUE"
$SEC"1"
CDS_SEC"1";
"1_P"
$PN"1"59;
"3_G"
$PN"3"15;
"2_N"
$PN"2"60;
%"UNIVERSAL_GND"
"1","(-2900,50)","0","logical_power","I2";
;
HDL_POWER"DELTA_L_GND_1"
CDS_LIB"logical_power";
"A"2;
%"PICOPROBE_BXA"
"1","(-350,1675)","4","pure_quanta","I20";
;
PART_NUMBER"TP33"
MATERIAL"EMPTY"
VALUE"DELTA-L 4.0"
PART_TYPE"SMLF"
LOCATION"J73"
CDS_LIB"pure_quanta"
CDS_LMAN_SYM_OUTLINE"-150,100,150,-100"
NEEDS_NO_SIZE"TRUE"
$SEC"1"
CDS_SEC"1";
"1_P"
$PN"1"57;
"3_G"
$PN"3"16;
"2_N"
$PN"2"58;
%"PICOPROBE_BXA"
"1","(-350,2525)","4","pure_quanta","I21";
;
PART_NUMBER"TP33"
VALUE"DELTA-L 4.0"
PART_TYPE"SMLF"
MATERIAL"EMPTY"
LOCATION"J72"
NEEDS_NO_SIZE"TRUE"
CDS_LMAN_SYM_OUTLINE"-150,100,150,-100"
CDS_LIB"pure_quanta"
$SEC"1"
CDS_SEC"1";
"1_P"
$PN"1"55;
"3_G"
$PN"3"17;
"2_N"
$PN"2"56;
%"PICOPROBE_BXA"
"1","(-350,3100)","4","pure_quanta","I22";
;
PART_NUMBER"TP33"
MATERIAL"EMPTY"
VALUE"DELTA-L 4.0"
PART_TYPE"SMLF"
LOCATION"J71"
NEEDS_NO_SIZE"TRUE"
CDS_LMAN_SYM_OUTLINE"-150,100,150,-100"
CDS_LIB"pure_quanta"
$SEC"1"
CDS_SEC"1";
"1_P"
$PN"1"53;
"3_G"
$PN"3"21;
"2_N"
$PN"2"54;
%"PICOPROBE_BXA"
"1","(-350,4000)","4","pure_quanta","I23";
;
PART_NUMBER"TP33"
VALUE"DELTA-L 4.0"
MATERIAL"EMPTY"
PART_TYPE"SMLF"
LOCATION"J70"
NEEDS_NO_SIZE"TRUE"
CDS_LMAN_SYM_OUTLINE"-150,100,150,-100"
CDS_LIB"pure_quanta"
$SEC"1"
CDS_SEC"1";
"1_P"
$PN"1"51;
"3_G"
$PN"3"22;
"2_N"
$PN"2"52;
%"PICOPROBE_BXA"
"1","(-325,4575)","4","pure_quanta","I24";
;
PART_NUMBER"TP33"
MATERIAL"EMPTY"
PART_TYPE"SMLF"
VALUE"DELTA-L 4.0"
LOCATION"J69"
NEEDS_NO_SIZE"TRUE"
CDS_LMAN_SYM_OUTLINE"-150,100,150,-100"
CDS_LIB"pure_quanta"
$SEC"1"
CDS_SEC"1";
"1_P"
$PN"1"50;
"3_G"
$PN"3"23;
"2_N"
$PN"2"49;
%"UNIVERSAL_GND"
"1","(250,-475)","0","logical_power","I25";
;
HDL_POWER"DELTA_L_GND_1"
CDS_LIB"logical_power";
"A"9;
%"UNIVERSAL_GND"
"1","(250,100)","0","logical_power","I26";
;
HDL_POWER"DELTA_L_GND_1"
CDS_LIB"logical_power";
"A"10;
%"UNIVERSAL_GND"
"1","(1300,-500)","0","logical_power","I27";
;
HDL_POWER"DELTA_L_GND_1"
CDS_LIB"logical_power";
"A"11;
%"PICOPROBE_BXA"
"1","(1850,-325)","0","pure_quanta","I28";
;
PART_NUMBER"TP33"
MATERIAL"EMPTY"
PART_TYPE"SMLF"
VALUE"DELTA-L 4.0"
LOCATION"J119"
NEEDS_NO_SIZE"TRUE"
CDS_LMAN_SYM_OUTLINE"-150,100,150,-100"
CDS_LIB"pure_quanta"
$SEC"1"
CDS_SEC"1";
"1_P"
$PN"1"46;
"3_G"
$PN"3"11;
"2_N"
$PN"2"45;
%"UNIVERSAL_GND"
"1","(1300,75)","0","logical_power","I29";
;
HDL_POWER"DELTA_L_GND_1"
CDS_LIB"logical_power";
"A"12;
%"PICOPROBE_BXA"
"1","(-2350,-350)","0","pure_quanta","I3";
;
PART_NUMBER"TP33"
MATERIAL"EMPTY"
PART_TYPE"SMLF"
VALUE"DELTA-L 4.0"
LOCATION"J115"
CDS_LIB"pure_quanta"
CDS_LMAN_SYM_OUTLINE"-150,100,150,-100"
NEEDS_NO_SIZE"TRUE"
$SEC"1"
CDS_SEC"1";
"1_P"
$PN"1"64;
"3_G"
$PN"3"1;
"2_N"
$PN"2"63;
%"PICOPROBE_BXA"
"1","(1850,250)","0","pure_quanta","I30";
;
PART_NUMBER"TP33"
PART_TYPE"SMLF"
MATERIAL"EMPTY"
VALUE"DELTA-L 4.0"
LOCATION"J118"
NEEDS_NO_SIZE"TRUE"
CDS_LMAN_SYM_OUTLINE"-150,100,150,-100"
CDS_LIB"pure_quanta"
$SEC"1"
CDS_SEC"1";
"1_P"
$PN"1"48;
"3_G"
$PN"3"12;
"2_N"
$PN"2"47;
%"PICOPROBE_BXA"
"1","(3900,-275)","4","pure_quanta","I31";
;
PART_NUMBER"TP33"
VALUE"DELTA-L 4.0"
PART_TYPE"SMLF"
MATERIAL"EMPTY"
LOCATION"J121"
CDS_LIB"pure_quanta"
CDS_LMAN_SYM_OUTLINE"-150,100,150,-100"
NEEDS_NO_SIZE"TRUE"
$SEC"1"
CDS_SEC"1";
"1_P"
$PN"1"45;
"3_G"
$PN"3"13;
"2_N"
$PN"2"46;
%"PICOPROBE_BXA"
"1","(3900,300)","4","pure_quanta","I32";
;
PART_NUMBER"TP33"
VALUE"DELTA-L 4.0"
PART_TYPE"SMLF"
MATERIAL"EMPTY"
LOCATION"J120"
CDS_LIB"pure_quanta"
CDS_LMAN_SYM_OUTLINE"-150,100,150,-100"
NEEDS_NO_SIZE"TRUE"
$SEC"1"
CDS_SEC"1";
"1_P"
$PN"1"47;
"3_G"
$PN"3"14;
"2_N"
$PN"2"48;
%"UNIVERSAL_GND"
"1","(4450,-450)","0","logical_power","I33";
;
HDL_POWER"DELTA_L_GND_1"
CDS_LIB"logical_power";
"A"13;
%"UNIVERSAL_GND"
"1","(4450,125)","0","logical_power","I34";
;
HDL_POWER"DELTA_L_GND_1"
CDS_LIB"logical_power";
"A"14;
%"UNIVERSAL_GND"
"1","(200,925)","0","logical_power","I35";
;
HDL_POWER"DELTA_L_GND_1"
CDS_LIB"logical_power";
"A"15;
%"UNIVERSAL_GND"
"1","(200,1500)","0","logical_power","I36";
;
HDL_POWER"DELTA_L_GND_1"
CDS_LIB"logical_power";
"A"16;
%"UNIVERSAL_GND"
"1","(200,2350)","0","logical_power","I37";
;
HDL_POWER"DELTA_L_GND_1"
CDS_LIB"logical_power";
"A"17;
%"UNIVERSAL_GND"
"1","(1225,875)","0","logical_power","I38";
;
HDL_POWER"DELTA_L_GND_1"
CDS_LIB"logical_power";
"A"18;
%"PICOPROBE_BXA"
"1","(1775,1050)","0","pure_quanta","I39";
;
PART_NUMBER"TP33"
MATERIAL"EMPTY"
VALUE"DELTA-L 4.0"
PART_TYPE"SMLF"
LOCATION"J80"
NEEDS_NO_SIZE"TRUE"
CDS_LMAN_SYM_OUTLINE"-150,100,150,-100"
CDS_LIB"pure_quanta"
$SEC"1"
CDS_SEC"1";
"1_P"
$PN"1"42;
"3_G"
$PN"3"18;
"2_N"
$PN"2"41;
%"PICOPROBE_BXA"
"1","(-2350,225)","0","pure_quanta","I4";
;
PART_NUMBER"TP33"
PART_TYPE"SMLF"
MATERIAL"EMPTY"
VALUE"DELTA-L 4.0"
LOCATION"J114"
NEEDS_NO_SIZE"TRUE"
CDS_LMAN_SYM_OUTLINE"-150,100,150,-100"
CDS_LIB"pure_quanta"
$SEC"1"
CDS_SEC"1";
"1_P"
$PN"1"62;
"3_G"
$PN"3"2;
"2_N"
$PN"2"61;
%"UNIVERSAL_GND"
"1","(1225,1450)","0","logical_power","I40";
;
HDL_POWER"DELTA_L_GND_1"
CDS_LIB"logical_power";
"A"19;
%"UNIVERSAL_GND"
"1","(1225,2300)","0","logical_power","I41";
;
HDL_POWER"DELTA_L_GND_1"
CDS_LIB"logical_power";
"A"20;
%"PICOPROBE_BXA"
"1","(1775,1625)","0","pure_quanta","I42";
;
PART_NUMBER"TP33"
MATERIAL"EMPTY"
VALUE"DELTA-L 4.0"
PART_TYPE"SMLF"
LOCATION"J79"
NEEDS_NO_SIZE"TRUE"
CDS_LMAN_SYM_OUTLINE"-150,100,150,-100"
CDS_LIB"pure_quanta"
$SEC"1"
CDS_SEC"1";
"1_P"
$PN"1"44;
"3_G"
$PN"3"19;
"2_N"
$PN"2"43;
%"PICOPROBE_BXA"
"1","(1775,2475)","0","pure_quanta","I43";
;
PART_NUMBER"TP33"
MATERIAL"EMPTY"
PART_TYPE"SMLF"
VALUE"DELTA-L 4.0"
LOCATION"J78"
NEEDS_NO_SIZE"TRUE"
CDS_LMAN_SYM_OUTLINE"-150,100,150,-100"
CDS_LIB"pure_quanta"
$SEC"1"
CDS_SEC"1";
"1_P"
$PN"1"36;
"3_G"
$PN"3"20;
"2_N"
$PN"2"35;
%"UNIVERSAL_GND"
"1","(200,2925)","0","logical_power","I44";
;
HDL_POWER"DELTA_L_GND_1"
CDS_LIB"logical_power";
"A"21;
%"UNIVERSAL_GND"
"1","(200,3825)","0","logical_power","I45";
;
HDL_POWER"DELTA_L_GND_1"
CDS_LIB"logical_power";
"A"22;
%"UNIVERSAL_GND"
"1","(225,4400)","0","logical_power","I46";
;
HDL_POWER"DELTA_L_GND_1"
CDS_LIB"logical_power";
"A"23;
%"UNIVERSAL_GND"
"1","(1225,2875)","0","logical_power","I47";
;
HDL_POWER"DELTA_L_GND_1"
CDS_LIB"logical_power";
"A"24;
%"PICOPROBE_BXA"
"1","(1775,3050)","0","pure_quanta","I48";
;
PART_NUMBER"TP33"
MATERIAL"EMPTY"
VALUE"DELTA-L 4.0"
PART_TYPE"SMLF"
LOCATION"J77"
CDS_LIB"pure_quanta"
CDS_LMAN_SYM_OUTLINE"-150,100,150,-100"
NEEDS_NO_SIZE"TRUE"
$SEC"1"
CDS_SEC"1";
"1_P"
$PN"1"38;
"3_G"
$PN"3"24;
"2_N"
$PN"2"37;
%"UNIVERSAL_GND"
"1","(1225,3775)","0","logical_power","I49";
;
HDL_POWER"DELTA_L_GND_1"
CDS_LIB"logical_power";
"A"25;
%"PICOPROBE_BXA"
"1","(-300,-300)","4","pure_quanta","I5";
;
PART_NUMBER"TP33"
VALUE"DELTA-L 4.0"
PART_TYPE"SMLF"
MATERIAL"EMPTY"
LOCATION"J117"
CDS_LIB"pure_quanta"
CDS_LMAN_SYM_OUTLINE"-150,100,150,-100"
NEEDS_NO_SIZE"TRUE"
$SEC"1"
CDS_SEC"1";
"1_P"
$PN"1"63;
"3_G"
$PN"3"9;
"2_N"
$PN"2"64;
%"UNIVERSAL_GND"
"1","(1225,4350)","0","logical_power","I50";
;
HDL_POWER"DELTA_L_GND_1"
CDS_LIB"logical_power";
"A"26;
%"PICOPROBE_BXA"
"1","(1775,3950)","0","pure_quanta","I51";
;
PART_NUMBER"TP33"
MATERIAL"EMPTY"
PART_TYPE"SMLF"
VALUE"DELTA-L 4.0"
LOCATION"J76"
CDS_LIB"pure_quanta"
CDS_LMAN_SYM_OUTLINE"-150,100,150,-100"
NEEDS_NO_SIZE"TRUE"
$SEC"1"
CDS_SEC"1";
"1_P"
$PN"1"40;
"3_G"
$PN"3"25;
"2_N"
$PN"2"39;
%"PICOPROBE_BXA"
"1","(1775,4525)","0","pure_quanta","I52";
;
PART_NUMBER"TP33"
MATERIAL"EMPTY"
VALUE"DELTA-L 4.0"
PART_TYPE"SMLF"
LOCATION"J75"
CDS_LMAN_SYM_OUTLINE"-150,100,150,-100"
NEEDS_NO_SIZE"TRUE"
CDS_LIB"pure_quanta"
$SEC"1"
CDS_SEC"1";
"1_P"
$PN"1"33;
"3_G"
$PN"3"26;
"2_N"
$PN"2"34;
%"PICOPROBE_BXA"
"1","(3825,1100)","4","pure_quanta","I53";
;
PART_NUMBER"TP33"
MATERIAL"EMPTY"
PART_TYPE"SMLF"
VALUE"DELTA-L 4.0"
LOCATION"J86"
NEEDS_NO_SIZE"TRUE"
CDS_LMAN_SYM_OUTLINE"-150,100,150,-100"
CDS_LIB"pure_quanta"
$SEC"1"
CDS_SEC"1";
"1_P"
$PN"1"41;
"3_G"
$PN"3"27;
"2_N"
$PN"2"42;
%"PICOPROBE_BXA"
"1","(3825,1675)","4","pure_quanta","I54";
;
PART_NUMBER"TP33"
VALUE"DELTA-L 4.0"
PART_TYPE"SMLF"
MATERIAL"EMPTY"
LOCATION"J85"
NEEDS_NO_SIZE"TRUE"
CDS_LMAN_SYM_OUTLINE"-150,100,150,-100"
CDS_LIB"pure_quanta"
$SEC"1"
CDS_SEC"1";
"1_P"
$PN"1"43;
"3_G"
$PN"3"28;
"2_N"
$PN"2"44;
%"PICOPROBE_BXA"
"1","(3825,2525)","4","pure_quanta","I55";
;
PART_NUMBER"TP33"
VALUE"DELTA-L 4.0"
PART_TYPE"SMLF"
MATERIAL"EMPTY"
LOCATION"J84"
NEEDS_NO_SIZE"TRUE"
CDS_LMAN_SYM_OUTLINE"-150,100,150,-100"
CDS_LIB"pure_quanta"
$SEC"1"
CDS_SEC"1";
"1_P"
$PN"1"35;
"3_G"
$PN"3"29;
"2_N"
$PN"2"36;
%"PICOPROBE_BXA"
"1","(3825,3100)","4","pure_quanta","I56";
;
PART_NUMBER"TP33"
MATERIAL"EMPTY"
PART_TYPE"SMLF"
VALUE"DELTA-L 4.0"
LOCATION"J83"
NEEDS_NO_SIZE"TRUE"
CDS_LMAN_SYM_OUTLINE"-150,100,150,-100"
CDS_LIB"pure_quanta"
$SEC"1"
CDS_SEC"1";
"1_P"
$PN"1"37;
"3_G"
$PN"3"30;
"2_N"
$PN"2"38;
%"PICOPROBE_BXA"
"1","(3825,4000)","4","pure_quanta","I57";
;
PART_NUMBER"TP33"
MATERIAL"EMPTY"
PART_TYPE"SMLF"
VALUE"DELTA-L 4.0"
LOCATION"J82"
NEEDS_NO_SIZE"TRUE"
CDS_LMAN_SYM_OUTLINE"-150,100,150,-100"
CDS_LIB"pure_quanta"
$SEC"1"
CDS_SEC"1";
"1_P"
$PN"1"39;
"3_G"
$PN"3"31;
"2_N"
$PN"2"40;
%"PICOPROBE_BXA"
"1","(3825,4575)","4","pure_quanta","I58";
;
PART_NUMBER"TP33"
PART_TYPE"SMLF"
MATERIAL"EMPTY"
VALUE"DELTA-L 4.0"
LOCATION"J81"
CDS_LIB"pure_quanta"
CDS_LMAN_SYM_OUTLINE"-150,100,150,-100"
NEEDS_NO_SIZE"TRUE"
$SEC"1"
CDS_SEC"1";
"1_P"
$PN"1"34;
"3_G"
$PN"3"32;
"2_N"
$PN"2"33;
%"UNIVERSAL_GND"
"1","(4375,925)","0","logical_power","I59";
;
HDL_POWER"DELTA_L_GND_1"
CDS_LIB"logical_power";
"A"27;
%"PICOPROBE_BXA"
"1","(-300,275)","4","pure_quanta","I6";
;
PART_NUMBER"TP33"
VALUE"DELTA-L 4.0"
PART_TYPE"SMLF"
MATERIAL"EMPTY"
LOCATION"J116"
CDS_LIB"pure_quanta"
CDS_LMAN_SYM_OUTLINE"-150,100,150,-100"
NEEDS_NO_SIZE"TRUE"
$SEC"1"
CDS_SEC"1";
"1_P"
$PN"1"61;
"3_G"
$PN"3"10;
"2_N"
$PN"2"62;
%"UNIVERSAL_GND"
"1","(4375,1500)","0","logical_power","I60";
;
HDL_POWER"DELTA_L_GND_1"
CDS_LIB"logical_power";
"A"28;
%"UNIVERSAL_GND"
"1","(4375,2350)","0","logical_power","I61";
;
HDL_POWER"DELTA_L_GND_1"
CDS_LIB"logical_power";
"A"29;
%"UNIVERSAL_GND"
"1","(4375,2925)","0","logical_power","I62";
;
HDL_POWER"DELTA_L_GND_1"
CDS_LIB"logical_power";
"A"30;
%"UNIVERSAL_GND"
"1","(4375,3825)","0","logical_power","I63";
;
HDL_POWER"DELTA_L_GND_1"
CDS_LIB"logical_power";
"A"31;
%"UNIVERSAL_GND"
"1","(4375,4400)","0","logical_power","I64";
;
HDL_POWER"DELTA_L_GND_1"
CDS_LIB"logical_power";
"A"32;
%"UNIVERSAL_GND"
"1","(-2950,875)","0","logical_power","I7";
;
HDL_POWER"DELTA_L_GND_1"
CDS_LIB"logical_power";
"A"3;
%"PICOPROBE_BXA"
"1","(-2400,1050)","0","pure_quanta","I8";
;
PART_NUMBER"TP33"
PART_TYPE"SMLF"
MATERIAL"EMPTY"
VALUE"DELTA-L 4.0"
LOCATION"J68"
NEEDS_NO_SIZE"TRUE"
CDS_LMAN_SYM_OUTLINE"-150,100,150,-100"
CDS_LIB"pure_quanta"
$SEC"1"
CDS_SEC"1";
"1_P"
$PN"1"60;
"3_G"
$PN"3"3;
"2_N"
$PN"2"59;
%"UNIVERSAL_GND"
"1","(-2950,1450)","0","logical_power","I9";
;
HDL_POWER"DELTA_L_GND_1"
CDS_LIB"logical_power";
"A"4;
END.
